# BASEBOARD_FAB2 (Tioga Pass) — schematic netlist excerpt (pin names and nets, part order shuffled) for the footprints in the layout excerpt that follows; sources: Cadence DE-HDL packaged netlist, KiCad conversion of Wiwynn_Tioga_Pass_MB.brd

R9G18  RES  0.0 5% CHIP  pkg 0402  page 141 : A = NIC_SET_P_MDI_2_DP ; B = NIC_MDI_SPRV_RJ45_2_R_DP
L1A2  IND-120NH-30-GP  pkg DISCRET-GB2  page 227 : S = VR_PVDDQ_KLM_PH1_SW ; F = PVDDQ_KLM
RT32  1R3F-GP  1%  pkg RCL_GP  page 219 : \1\ = VR_PVDDQ_DEF_PH2_SW_RC ; \2\ = GND

(kicad_pcb
	(version 20260206)
	(generator "pcbnew")
	(generator_version "10.0")
	(general
		(thickness 1.6)
		(legacy_teardrops no)
	)
	(paper "A4")
	(title_block
		(title "Wiwynn_Tioga_Pass_MB.brd")
		(comment 1 "Tioga Pass / footprints 2000-2002 of 4770")
	)
	(layers
		(0 "F.Cu" signal "TOP")
		(4 "In1.Cu" signal "L2GND")
		(6 "In2.Cu" signal "L3")
		(8 "In3.Cu" signal "L4GND")
		(10 "In4.Cu" signal "L5")
		(12 "In5.Cu" signal "L6GND")
		(14 "In6.Cu" signal "L7VCC")
		(16 "In7.Cu" signal "L8VCC")
		(18 "In8.Cu" signal "L9GND")
		(20 "In9.Cu" signal "L10")
		(22 "In10.Cu" signal "L11GND")
		(24 "In11.Cu" signal "L12")
		(26 "In12.Cu" signal "L13GND")
		(2 "B.Cu" signal "BOTTOM")
		(9 "F.Adhes" user "F.Adhesive")
		(11 "B.Adhes" user "B.Adhesive")
		(13 "F.Paste" user "Package Geometry/Pastemask Top")
		(15 "B.Paste" user "Package Geometry/Pastemask Bottom")
		(5 "F.SilkS" user "Ref Des/Silkscreen Top")
		(7 "B.SilkS" user "Ref Des/Silkscreen Bottom")
		(1 "F.Mask" user "Board Geometry/Soldermask Top")
		(3 "B.Mask" user "Board Geometry/Soldermask Bottom")
		(17 "Dwgs.User" user "User.Drawings")
		(19 "Cmts.User" user "User.Comments")
		(21 "Eco1.User" user "User.Eco1")
		(23 "Eco2.User" user "User.Eco2")
		(25 "Edge.Cuts" user "Board Geometry/Outline")
		(27 "Margin" user)
		(31 "F.CrtYd" user "Package Geometry/Place Bound Top")
		(29 "B.CrtYd" user "Package Geometry/Place Bound Bottom")
		(35 "F.Fab" user "Ref Des/Assembly Top")
		(33 "B.Fab" user "Ref Des/Assembly Bottom")
	)
	(footprint ""
		(layer "F.Cu")
		(at 344.0176 -141.224 90)
		(property "Reference" "RT32"
			(at 0 0 90)
			(layer "F.SilkS")
			(hide yes)
			(effects
				(font
					(size 1.27 1.27)
				)
			)
		)
		(property "Value" "*"
			(at -0.0254 -2.6289 90)
			(unlocked yes)
			(layer "F.Fab")
			(hide yes)
			(effects
				(font
					(size 1.27 1.016)
					(thickness 0.1524)
				)
			)
		)
		(property "Device Type" "1R3F-GP_RCL_GP-1R3F-GP,64.1R00A"
			(at -0.0254 -4.1529 90)
			(unlocked yes)
			(layer "F.Fab")
			(hide yes)
			(effects
				(font
					(size 1.27 1.016)
					(thickness 0.1524)
				)
			)
		)
		(duplicate_pad_numbers_are_jumpers no)
		(fp_line
			(start 0.2032 0)
			(end 0.4826 0)
			(stroke
				(width 0.2032)
				(type default)
			)
			(layer "F.SilkS")
		)
		(fp_line
			(start -0.4826 0)
			(end -0.2032 0)
			(stroke
				(width 0.2032)
				(type default)
			)
			(layer "F.SilkS")
		)
		(fp_rect
			(start -0.5842 1.3335)
			(end 0.5842 -1.3335)
			(stroke
				(width 0)
				(type default)
			)
			(fill no)
			(layer "F.CrtYd")
		)
		(fp_rect
			(start -0.5842 1.3335)
			(end 0.5842 -1.3335)
			(stroke
				(width 0)
				(type default)
			)
			(fill no)
			(layer "F.Fab")
		)
		(pad "1" smd custom
			(at 0 -0.762 90)
			(size 0.2159 0.2159)
			(layers "F.Cu" "F.Mask" "F.Paste")
			(net "VR_PVDDQ_DEF_PH2_SW_RC")
			(options
				(clearance outline)
				(anchor circle)
			)
			(primitives
				(gr_poly
					(pts
						(arc
							(start -0.3302 -0.4318)
							(mid -0.402042 -0.402042)
							(end -0.4318 -0.3302)
						)
						(arc
							(start -0.4318 0.3302)
							(mid -0.402042 0.402042)
							(end -0.3302 0.4318)
						)
						(arc
							(start 0.3302 0.4318)
							(mid 0.402042 0.402042)
							(end 0.4318 0.3302)
						)
						(arc
							(start 0.4318 -0.3302)
							(mid 0.402042 -0.402042)
							(end 0.3302 -0.4318)
						)
					)
					(width 0)
					(fill yes)
				)
			)
		)
		(pad "2" smd custom
			(at 0 0.762 90)
			(size 0.2159 0.2159)
			(layers "F.Cu" "F.Mask" "F.Paste")
			(net "GND")
			(options
				(clearance outline)
				(anchor circle)
			)
			(primitives
				(gr_poly
					(pts
						(arc
							(start -0.3302 -0.4318)
							(mid -0.402042 -0.402042)
							(end -0.4318 -0.3302)
						)
						(arc
							(start -0.4318 0.3302)
							(mid -0.402042 0.402042)
							(end -0.3302 0.4318)
						)
						(arc
							(start 0.3302 0.4318)
							(mid 0.402042 0.402042)
							(end 0.4318 0.3302)
						)
						(arc
							(start 0.4318 -0.3302)
							(mid 0.402042 -0.402042)
							(end 0.3302 -0.4318)
						)
					)
					(width 0)
					(fill yes)
				)
			)
		)
	)
	(footprint ""
		(layer "F.Cu")
		(at 8.4074 -138.2014)
		(property "Reference" "L1A2"
			(at 3.378708 -4.251706 0)
			(unlocked yes)
			(layer "F.SilkS")
			(effects
				(font
					(size 0.4064 0.254)
					(thickness 0.1524)
				)
			)
		)
		(property "Value" ""
			(at 0 0 0)
			(layer "F.Fab")
			(effects
				(font
					(size 1.27 1.27)
				)
			)
		)
		(duplicate_pad_numbers_are_jumpers no)
		(fp_line
			(start -1.1303 -3.199892)
			(end 8.3693 -3.199892)
			(stroke
				(width 0.1524)
				(type default)
			)
			(layer "F.SilkS")
		)
		(fp_line
			(start -1.1303 -1.6637)
			(end -1.1303 -3.199892)
			(stroke
				(width 0.1524)
				(type default)
			)
			(layer "F.SilkS")
		)
		(fp_line
			(start -1.1303 3.199892)
			(end -1.1303 1.6637)
			(stroke
				(width 0.1524)
				(type default)
			)
			(layer "F.SilkS")
		)
		(fp_line
			(start 8.3693 -3.199892)
			(end 8.3693 -1.6637)
			(stroke
				(width 0.1524)
				(type default)
			)
			(layer "F.SilkS")
		)
		(fp_line
			(start 8.3693 1.6637)
			(end 8.3693 3.199892)
			(stroke
				(width 0.1524)
				(type default)
			)
			(layer "F.SilkS")
		)
		(fp_line
			(start 8.3693 3.199892)
			(end -1.1303 3.199892)
			(stroke
				(width 0.1524)
				(type default)
			)
			(layer "F.SilkS")
		)
		(fp_rect
			(start -1.1303 3.199892)
			(end 8.3693 -3.199892)
			(stroke
				(width 0)
				(type default)
			)
			(fill no)
			(layer "F.CrtYd")
		)
		(fp_line
			(start -1.1303 -3.199892)
			(end 8.3693 -3.199892)
			(stroke
				(width 0.1)
				(type default)
			)
			(layer "F.Fab")
		)
		(fp_line
			(start -1.1303 3.199892)
			(end -1.1303 -3.199892)
			(stroke
				(width 0.1)
				(type default)
			)
			(layer "F.Fab")
		)
		(fp_line
			(start 8.3693 -3.199892)
			(end 8.3693 3.199892)
			(stroke
				(width 0.1)
				(type default)
			)
			(layer "F.Fab")
		)
		(fp_line
			(start 8.3693 3.199892)
			(end -1.1303 3.199892)
			(stroke
				(width 0.1)
				(type default)
			)
			(layer "F.Fab")
		)
		(pad "1" smd rect
			(at 0 0)
			(size 3.683 2.667)
			(layers "F.Cu" "F.Mask" "F.Paste")
			(net "VR_PVDDQ_KLM_PH1_SW")
		)
		(pad "2" smd rect
			(at 7.239 0)
			(size 3.683 2.667)
			(layers "F.Cu" "F.Mask" "F.Paste")
			(net "PVDDQ_KLM")
		)
	)
	(footprint ""
		(layer "F.Cu")
		(at 480.842574 4.65709 -90)
		(property "Reference" "R9G18"
			(at 0 0 270)
			(layer "F.SilkS")
			(hide yes)
			(effects
				(font
					(size 1.27 1.27)
				)
			)
		)
		(property "Value" ""
			(at 0 0 270)
			(layer "F.Fab")
			(effects
				(font
					(size 1.27 1.27)
				)
			)
		)
		(duplicate_pad_numbers_are_jumpers no)
		(fp_poly
			(pts
				(xy -0.2794 -0.1016) (xy 0.2794 -0.1016) (xy 0.2794 0.9906) (xy -0.2794 0.9906)
			)
			(stroke
				(width 0)
				(type default)
			)
			(fill no)
			(layer "F.CrtYd")
		)
		(fp_line
			(start -0.2794 0.9906)
			(end 0.2794 0.9906)
			(stroke
				(width 0.1)
				(type default)
			)
			(layer "F.Fab")
		)
		(fp_line
			(start 0.2794 0.9906)
			(end 0.2794 -0.1016)
			(stroke
				(width 0.1)
				(type default)
			)
			(layer "F.Fab")
		)
		(fp_line
			(start -0.2794 -0.1016)
			(end -0.2794 0.9906)
			(stroke
				(width 0.1)
				(type default)
			)
			(layer "F.Fab")
		)
		(fp_line
			(start 0.2794 -0.1016)
			(end -0.2794 -0.1016)
			(stroke
				(width 0.1)
				(type default)
			)
			(layer "F.Fab")
		)
		(pad "1" smd rect
			(at 0 0 270)
			(size 0.508 0.508)
			(layers "F.Cu" "F.Mask" "F.Paste")
			(net "NIC_SET_P_MDI_2_DP")
		)
		(pad "2" smd rect
			(at 0 0.889 270)
			(size 0.508 0.508)
			(layers "F.Cu" "F.Mask" "F.Paste")
			(net "NIC_MDI_SPRV_RJ45_2_R_DP")
		)
		(zone
			(layer "F.Cu")
			(hatch none 0.5)
			(connect_pads
				(clearance 0)
			)
			(min_thickness 0.25)
			(keepout
				(tracks not_allowed)
				(vias allowed)
				(pads allowed)
				(copperpour not_allowed)
				(footprints allowed)
			)
			(placement
				(enabled no)
				(sheetname "")
			)
			(fill
				(thermal_gap 0.5)
				(thermal_bridge_width 0.5)
				(island_removal_mode 0)
			)
			(polygon
				(pts
					(xy 480.207574 4.40309) (xy 480.207574 4.91109) (xy 480.588574 4.91109) (xy 480.588574 4.40309)
				)
			)
		)
		(zone
			(layer "F.Cu")
			(hatch none 0.5)
			(connect_pads
				(clearance 0)
			)
			(min_thickness 0.25)
			(keepout
				(tracks allowed)
				(vias not_allowed)
				(pads allowed)
				(copperpour not_allowed)
				(footprints allowed)
			)
			(placement
				(enabled no)
				(sheetname "")
			)
			(fill
				(thermal_gap 0.5)
				(thermal_bridge_width 0.5)
				(island_removal_mode 0)
			)
			(polygon
				(pts
					(xy 480.588574 4.40309) (xy 480.588574 4.91109) (xy 480.207574 4.91109) (xy 480.207574 4.40309)
				)
			)
		)
	)
)
